(kicad_pcb
	(version 20260206)
	(generator "pcbnew")
	(generator_version "10.0")
	(general
		(thickness 1.6)
		(legacy_teardrops no)
	)
	(paper "A4")
	(title_block
		(title "01162023_DA0F0TEBIF0_F0T_Expander_BD_F_brd_V02_OCP.brd")
		(comment 1 "Grand Teton / footprints 1100-1105 of 9728")
	)
	(layers
		(0 "F.Cu" signal "TOP")
		(4 "In1.Cu" signal "GND")
		(6 "In2.Cu" signal "VCC")
		(8 "In3.Cu" signal "VCC1")
		(10 "In4.Cu" signal "GND1")
		(12 "In5.Cu" signal "IN1")
		(14 "In6.Cu" signal "GND2")
		(16 "In7.Cu" signal "IN2")
		(18 "In8.Cu" signal "GND3")
		(20 "In9.Cu" signal "IN3")
		(22 "In10.Cu" signal "GND4")
		(24 "In11.Cu" signal "IN4")
		(26 "In12.Cu" signal "GND5")
		(28 "In13.Cu" signal "IN5")
		(30 "In14.Cu" signal "GND6")
		(32 "In15.Cu" signal "IN6")
		(34 "In16.Cu" signal "GND7")
		(2 "B.Cu" signal "BOTTOM")
		(9 "F.Adhes" user "F.Adhesive")
		(11 "B.Adhes" user "B.Adhesive")
		(13 "F.Paste" user "Package Geometry/Pastemask Top")
		(15 "B.Paste" user "Package Geometry/Pastemask Bottom")
		(5 "F.SilkS" user "Ref Des/Silkscreen Top")
		(7 "B.SilkS" user "Ref Des/Silkscreen Bottom")
		(1 "F.Mask" user "Board Geometry/Soldermask Top")
		(3 "B.Mask" user "Board Geometry/Soldermask Bottom")
		(17 "Dwgs.User" user "User.Drawings")
		(19 "Cmts.User" user "User.Comments")
		(21 "Eco1.User" user "User.Eco1")
		(23 "Eco2.User" user "User.Eco2")
		(25 "Edge.Cuts" user "Board Geometry/Outline")
		(27 "Margin" user)
		(31 "F.CrtYd" user "Package Geometry/Place Bound Top")
		(29 "B.CrtYd" user "Package Geometry/Place Bound Bottom")
		(35 "F.Fab" user "Ref Des/Assembly Top")
		(33 "B.Fab" user "Ref Des/Assembly Bottom")
	)
	(footprint ""
		(layer "F.Cu")
		(at 451.36435 -29.079952 180)
		(property "Reference" "R6213"
			(at 0 0 180)
			(layer "F.SilkS")
			(hide yes)
			(effects
				(font
					(size 1.27 1.27)
				)
			)
		)
		(property "Value" ""
			(at 0 0 180)
			(layer "F.Fab")
			(effects
				(font
					(size 1.27 1.27)
				)
			)
		)
		(duplicate_pad_numbers_are_jumpers no)
		(fp_line
			(start 0.7874 0.4064)
			(end -0.7874 0.4064)
			(stroke
				(width 0.1524)
				(type default)
			)
			(layer "F.SilkS")
		)
		(fp_line
			(start 0.7874 -0.4064)
			(end 0.7874 0.4064)
			(stroke
				(width 0.1524)
				(type default)
			)
			(layer "F.SilkS")
		)
		(fp_line
			(start -0.7874 0.4064)
			(end -0.7874 -0.4064)
			(stroke
				(width 0.1524)
				(type default)
			)
			(layer "F.SilkS")
		)
		(fp_line
			(start -0.7874 -0.4064)
			(end 0.7874 -0.4064)
			(stroke
				(width 0.1524)
				(type default)
			)
			(layer "F.SilkS")
		)
		(fp_line
			(start 0.67945 0.3048)
			(end 0.120396 0.3048)
			(stroke
				(width 0.1)
				(type default)
			)
			(layer "F.Fab")
		)
		(fp_line
			(start 0.67945 -0.3048)
			(end 0.67945 0.3048)
			(stroke
				(width 0.1)
				(type default)
			)
			(layer "F.Fab")
		)
		(fp_line
			(start 0.12065 -0.2794)
			(end 0.12065 -0.3048)
			(stroke
				(width 0.1)
				(type default)
			)
			(layer "F.Fab")
		)
		(fp_line
			(start 0.12065 -0.3048)
			(end 0.67945 -0.3048)
			(stroke
				(width 0.1)
				(type default)
			)
			(layer "F.Fab")
		)
		(fp_line
			(start 0.120396 0.3048)
			(end 0.120396 0.2794)
			(stroke
				(width 0.1)
				(type default)
			)
			(layer "F.Fab")
		)
		(fp_line
			(start 0.120396 0.2794)
			(end -0.12065 0.2794)
			(stroke
				(width 0.1)
				(type default)
			)
			(layer "F.Fab")
		)
		(fp_line
			(start -0.12065 0.3048)
			(end -0.67945 0.3048)
			(stroke
				(width 0.1)
				(type default)
			)
			(layer "F.Fab")
		)
		(fp_line
			(start -0.12065 0.2794)
			(end -0.12065 0.3048)
			(stroke
				(width 0.1)
				(type default)
			)
			(layer "F.Fab")
		)
		(fp_line
			(start -0.12065 -0.2794)
			(end 0.12065 -0.2794)
			(stroke
				(width 0.1)
				(type default)
			)
			(layer "F.Fab")
		)
		(fp_line
			(start -0.12065 -0.305054)
			(end -0.12065 -0.2794)
			(stroke
				(width 0.1)
				(type default)
			)
			(layer "F.Fab")
		)
		(fp_line
			(start -0.67945 0.3048)
			(end -0.67945 -0.305054)
			(stroke
				(width 0.1)
				(type default)
			)
			(layer "F.Fab")
		)
		(fp_line
			(start -0.67945 -0.305054)
			(end -0.12065 -0.305054)
			(stroke
				(width 0.1)
				(type default)
			)
			(layer "F.Fab")
		)
		(pad "1" smd circle
			(at -0.40005 0 180)
			(size 0 0)
			(layers "F.Cu" "F.Mask" "F.Paste")
			(net "GND")
		)
		(pad "2" smd circle
			(at 0.40005 0 180)
			(size 0 0)
			(layers "F.Cu" "F.Mask" "F.Paste")
			(net "SSD15_PWRDIS_R")
		)
	)
	(footprint ""
		(layer "F.Cu")
		(at 33.486344 -252.356874 -90)
		(property "Reference" "R1187"
			(at 0 0 270)
			(layer "F.SilkS")
			(hide yes)
			(effects
				(font
					(size 1.27 1.27)
				)
			)
		)
		(property "Value" ""
			(at 0 0 270)
			(layer "F.Fab")
			(effects
				(font
					(size 1.27 1.27)
				)
			)
		)
		(duplicate_pad_numbers_are_jumpers no)
		(fp_line
			(start -0.7874 0.4064)
			(end -0.7874 -0.4064)
			(stroke
				(width 0.1524)
				(type default)
			)
			(layer "F.SilkS")
		)
		(fp_line
			(start 0.7874 0.4064)
			(end -0.7874 0.4064)
			(stroke
				(width 0.1524)
				(type default)
			)
			(layer "F.SilkS")
		)
		(fp_line
			(start -0.7874 -0.4064)
			(end 0.7874 -0.4064)
			(stroke
				(width 0.1524)
				(type default)
			)
			(layer "F.SilkS")
		)
		(fp_line
			(start 0.7874 -0.4064)
			(end 0.7874 0.4064)
			(stroke
				(width 0.1524)
				(type default)
			)
			(layer "F.SilkS")
		)
		(fp_line
			(start -0.67945 0.3048)
			(end -0.67945 -0.305054)
			(stroke
				(width 0.1)
				(type default)
			)
			(layer "F.Fab")
		)
		(fp_line
			(start -0.12065 0.3048)
			(end -0.67945 0.3048)
			(stroke
				(width 0.1)
				(type default)
			)
			(layer "F.Fab")
		)
		(fp_line
			(start 0.120396 0.3048)
			(end 0.120396 0.2794)
			(stroke
				(width 0.1)
				(type default)
			)
			(layer "F.Fab")
		)
		(fp_line
			(start 0.67945 0.3048)
			(end 0.120396 0.3048)
			(stroke
				(width 0.1)
				(type default)
			)
			(layer "F.Fab")
		)
		(fp_line
			(start -0.12065 0.2794)
			(end -0.12065 0.3048)
			(stroke
				(width 0.1)
				(type default)
			)
			(layer "F.Fab")
		)
		(fp_line
			(start 0.120396 0.2794)
			(end -0.12065 0.2794)
			(stroke
				(width 0.1)
				(type default)
			)
			(layer "F.Fab")
		)
		(fp_line
			(start -0.12065 -0.2794)
			(end 0.12065 -0.2794)
			(stroke
				(width 0.1)
				(type default)
			)
			(layer "F.Fab")
		)
		(fp_line
			(start 0.12065 -0.2794)
			(end 0.12065 -0.3048)
			(stroke
				(width 0.1)
				(type default)
			)
			(layer "F.Fab")
		)
		(fp_line
			(start 0.12065 -0.3048)
			(end 0.67945 -0.3048)
			(stroke
				(width 0.1)
				(type default)
			)
			(layer "F.Fab")
		)
		(fp_line
			(start 0.67945 -0.3048)
			(end 0.67945 0.3048)
			(stroke
				(width 0.1)
				(type default)
			)
			(layer "F.Fab")
		)
		(fp_line
			(start -0.67945 -0.305054)
			(end -0.12065 -0.305054)
			(stroke
				(width 0.1)
				(type default)
			)
			(layer "F.Fab")
		)
		(fp_line
			(start -0.12065 -0.305054)
			(end -0.12065 -0.2794)
			(stroke
				(width 0.1)
				(type default)
			)
			(layer "F.Fab")
		)
		(pad "1" smd circle
			(at -0.40005 0 270)
			(size 0 0)
			(layers "F.Cu" "F.Mask" "F.Paste")
			(net "GND")
		)
		(pad "2" smd circle
			(at 0.40005 0 270)
			(size 0 0)
			(layers "F.Cu" "F.Mask" "F.Paste")
			(net "PEX0_DBG_MODE2")
		)
	)
	(footprint ""
		(layer "F.Cu")
		(at 230.749094 -173.67758 180)
		(property "Reference" "R3149"
			(at 0 0 180)
			(layer "F.SilkS")
			(hide yes)
			(effects
				(font
					(size 1.27 1.27)
				)
			)
		)
		(property "Value" ""
			(at 0 0 180)
			(layer "F.Fab")
			(effects
				(font
					(size 1.27 1.27)
				)
			)
		)
		(duplicate_pad_numbers_are_jumpers no)
		(fp_line
			(start 0.7874 0.4064)
			(end -0.7874 0.4064)
			(stroke
				(width 0.1524)
				(type default)
			)
			(layer "F.SilkS")
		)
		(fp_line
			(start 0.7874 -0.4064)
			(end 0.7874 0.4064)
			(stroke
				(width 0.1524)
				(type default)
			)
			(layer "F.SilkS")
		)
		(fp_line
			(start -0.7874 0.4064)
			(end -0.7874 -0.4064)
			(stroke
				(width 0.1524)
				(type default)
			)
			(layer "F.SilkS")
		)
		(fp_line
			(start -0.7874 -0.4064)
			(end 0.7874 -0.4064)
			(stroke
				(width 0.1524)
				(type default)
			)
			(layer "F.SilkS")
		)
		(fp_line
			(start 0.67945 0.3048)
			(end 0.120396 0.3048)
			(stroke
				(width 0.1)
				(type default)
			)
			(layer "F.Fab")
		)
		(fp_line
			(start 0.67945 -0.3048)
			(end 0.67945 0.3048)
			(stroke
				(width 0.1)
				(type default)
			)
			(layer "F.Fab")
		)
		(fp_line
			(start 0.12065 -0.2794)
			(end 0.12065 -0.3048)
			(stroke
				(width 0.1)
				(type default)
			)
			(layer "F.Fab")
		)
		(fp_line
			(start 0.12065 -0.3048)
			(end 0.67945 -0.3048)
			(stroke
				(width 0.1)
				(type default)
			)
			(layer "F.Fab")
		)
		(fp_line
			(start 0.120396 0.3048)
			(end 0.120396 0.2794)
			(stroke
				(width 0.1)
				(type default)
			)
			(layer "F.Fab")
		)
		(fp_line
			(start 0.120396 0.2794)
			(end -0.12065 0.2794)
			(stroke
				(width 0.1)
				(type default)
			)
			(layer "F.Fab")
		)
		(fp_line
			(start -0.12065 0.3048)
			(end -0.67945 0.3048)
			(stroke
				(width 0.1)
				(type default)
			)
			(layer "F.Fab")
		)
		(fp_line
			(start -0.12065 0.2794)
			(end -0.12065 0.3048)
			(stroke
				(width 0.1)
				(type default)
			)
			(layer "F.Fab")
		)
		(fp_line
			(start -0.12065 -0.2794)
			(end 0.12065 -0.2794)
			(stroke
				(width 0.1)
				(type default)
			)
			(layer "F.Fab")
		)
		(fp_line
			(start -0.12065 -0.305054)
			(end -0.12065 -0.2794)
			(stroke
				(width 0.1)
				(type default)
			)
			(layer "F.Fab")
		)
		(fp_line
			(start -0.67945 0.3048)
			(end -0.67945 -0.305054)
			(stroke
				(width 0.1)
				(type default)
			)
			(layer "F.Fab")
		)
		(fp_line
			(start -0.67945 -0.305054)
			(end -0.12065 -0.305054)
			(stroke
				(width 0.1)
				(type default)
			)
			(layer "F.Fab")
		)
		(pad "1" smd circle
			(at -0.40005 0 180)
			(size 0 0)
			(layers "F.Cu" "F.Mask" "F.Paste")
			(net "PWRGD_P1V2_AUX_DLY")
		)
		(pad "2" smd circle
			(at 0.40005 0 180)
			(size 0 0)
			(layers "F.Cu" "F.Mask" "F.Paste")
			(net "ADM1085_ENOUT")
		)
	)
	(footprint ""
		(layer "F.Cu")
		(at 393.546838 -38.49116 180)
		(property "Reference" "R6124"
			(at 0 0 180)
			(layer "F.SilkS")
			(hide yes)
			(effects
				(font
					(size 1.27 1.27)
				)
			)
		)
		(property "Value" ""
			(at 0 0 180)
			(layer "F.Fab")
			(effects
				(font
					(size 1.27 1.27)
				)
			)
		)
		(duplicate_pad_numbers_are_jumpers no)
		(fp_line
			(start 0.7874 0.4064)
			(end -0.7874 0.4064)
			(stroke
				(width 0.1524)
				(type default)
			)
			(layer "F.SilkS")
		)
		(fp_line
			(start 0.7874 -0.4064)
			(end 0.7874 0.4064)
			(stroke
				(width 0.1524)
				(type default)
			)
			(layer "F.SilkS")
		)
		(fp_line
			(start -0.7874 0.4064)
			(end -0.7874 -0.4064)
			(stroke
				(width 0.1524)
				(type default)
			)
			(layer "F.SilkS")
		)
		(fp_line
			(start -0.7874 -0.4064)
			(end 0.7874 -0.4064)
			(stroke
				(width 0.1524)
				(type default)
			)
			(layer "F.SilkS")
		)
		(fp_line
			(start 0.67945 0.3048)
			(end 0.120396 0.3048)
			(stroke
				(width 0.1)
				(type default)
			)
			(layer "F.Fab")
		)
		(fp_line
			(start 0.67945 -0.3048)
			(end 0.67945 0.3048)
			(stroke
				(width 0.1)
				(type default)
			)
			(layer "F.Fab")
		)
		(fp_line
			(start 0.12065 -0.2794)
			(end 0.12065 -0.3048)
			(stroke
				(width 0.1)
				(type default)
			)
			(layer "F.Fab")
		)
		(fp_line
			(start 0.12065 -0.3048)
			(end 0.67945 -0.3048)
			(stroke
				(width 0.1)
				(type default)
			)
			(layer "F.Fab")
		)
		(fp_line
			(start 0.120396 0.3048)
			(end 0.120396 0.2794)
			(stroke
				(width 0.1)
				(type default)
			)
			(layer "F.Fab")
		)
		(fp_line
			(start 0.120396 0.2794)
			(end -0.12065 0.2794)
			(stroke
				(width 0.1)
				(type default)
			)
			(layer "F.Fab")
		)
		(fp_line
			(start -0.12065 0.3048)
			(end -0.67945 0.3048)
			(stroke
				(width 0.1)
				(type default)
			)
			(layer "F.Fab")
		)
		(fp_line
			(start -0.12065 0.2794)
			(end -0.12065 0.3048)
			(stroke
				(width 0.1)
				(type default)
			)
			(layer "F.Fab")
		)
		(fp_line
			(start -0.12065 -0.2794)
			(end 0.12065 -0.2794)
			(stroke
				(width 0.1)
				(type default)
			)
			(layer "F.Fab")
		)
		(fp_line
			(start -0.12065 -0.305054)
			(end -0.12065 -0.2794)
			(stroke
				(width 0.1)
				(type default)
			)
			(layer "F.Fab")
		)
		(fp_line
			(start -0.67945 0.3048)
			(end -0.67945 -0.305054)
			(stroke
				(width 0.1)
				(type default)
			)
			(layer "F.Fab")
		)
		(fp_line
			(start -0.67945 -0.305054)
			(end -0.12065 -0.305054)
			(stroke
				(width 0.1)
				(type default)
			)
			(layer "F.Fab")
		)
		(pad "1" smd circle
			(at -0.40005 0 180)
			(size 0 0)
			(layers "F.Cu" "F.Mask" "F.Paste")
			(net "P3V3_SSD14_PG_G1")
		)
		(pad "2" smd circle
			(at 0.40005 0 180)
			(size 0 0)
			(layers "F.Cu" "F.Mask" "F.Paste")
			(net "GND")
		)
	)
	(footprint ""
		(layer "F.Cu")
		(at 204.591158 -80.611472)
		(property "Reference" "R4334"
			(at 0 0 0)
			(layer "F.SilkS")
			(hide yes)
			(effects
				(font
					(size 1.27 1.27)
				)
			)
		)
		(property "Value" ""
			(at 0 0 0)
			(layer "F.Fab")
			(effects
				(font
					(size 1.27 1.27)
				)
			)
		)
		(duplicate_pad_numbers_are_jumpers no)
		(fp_line
			(start -0.7874 -0.4064)
			(end 0.7874 -0.4064)
			(stroke
				(width 0.1524)
				(type default)
			)
			(layer "F.SilkS")
		)
		(fp_line
			(start -0.7874 0.4064)
			(end -0.7874 -0.4064)
			(stroke
				(width 0.1524)
				(type default)
			)
			(layer "F.SilkS")
		)
		(fp_line
			(start 0.7874 -0.4064)
			(end 0.7874 0.4064)
			(stroke
				(width 0.1524)
				(type default)
			)
			(layer "F.SilkS")
		)
		(fp_line
			(start 0.7874 0.4064)
			(end -0.7874 0.4064)
			(stroke
				(width 0.1524)
				(type default)
			)
			(layer "F.SilkS")
		)
		(fp_line
			(start -0.67945 -0.305054)
			(end -0.12065 -0.305054)
			(stroke
				(width 0.1)
				(type default)
			)
			(layer "F.Fab")
		)
		(fp_line
			(start -0.67945 0.3048)
			(end -0.67945 -0.305054)
			(stroke
				(width 0.1)
				(type default)
			)
			(layer "F.Fab")
		)
		(fp_line
			(start -0.12065 -0.305054)
			(end -0.12065 -0.2794)
			(stroke
				(width 0.1)
				(type default)
			)
			(layer "F.Fab")
		)
		(fp_line
			(start -0.12065 -0.2794)
			(end 0.12065 -0.2794)
			(stroke
				(width 0.1)
				(type default)
			)
			(layer "F.Fab")
		)
		(fp_line
			(start -0.12065 0.2794)
			(end -0.12065 0.3048)
			(stroke
				(width 0.1)
				(type default)
			)
			(layer "F.Fab")
		)
		(fp_line
			(start -0.12065 0.3048)
			(end -0.67945 0.3048)
			(stroke
				(width 0.1)
				(type default)
			)
			(layer "F.Fab")
		)
		(fp_line
			(start 0.120396 0.2794)
			(end -0.12065 0.2794)
			(stroke
				(width 0.1)
				(type default)
			)
			(layer "F.Fab")
		)
		(fp_line
			(start 0.120396 0.3048)
			(end 0.120396 0.2794)
			(stroke
				(width 0.1)
				(type default)
			)
			(layer "F.Fab")
		)
		(fp_line
			(start 0.12065 -0.3048)
			(end 0.67945 -0.3048)
			(stroke
				(width 0.1)
				(type default)
			)
			(layer "F.Fab")
		)
		(fp_line
			(start 0.12065 -0.2794)
			(end 0.12065 -0.3048)
			(stroke
				(width 0.1)
				(type default)
			)
			(layer "F.Fab")
		)
		(fp_line
			(start 0.67945 -0.3048)
			(end 0.67945 0.3048)
			(stroke
				(width 0.1)
				(type default)
			)
			(layer "F.Fab")
		)
		(fp_line
			(start 0.67945 0.3048)
			(end 0.120396 0.3048)
			(stroke
				(width 0.1)
				(type default)
			)
			(layer "F.Fab")
		)
		(pad "1" smd circle
			(at -0.40005 0)
			(size 0 0)
			(layers "F.Cu" "F.Mask" "F.Paste")
			(net "P3V3_AUX")
		)
		(pad "2" smd circle
			(at 0.40005 0)
			(size 0 0)
			(layers "F.Cu" "F.Mask" "F.Paste")
			(net "SSD4_LED_R")
		)
	)
	(footprint ""
		(layer "F.Cu")
		(at 247.359678 -152.71115 -90)
		(property "Reference" "R731"
			(at 0 0 270)
			(layer "F.SilkS")
			(hide yes)
			(effects
				(font
					(size 1.27 1.27)
				)
			)
		)
		(property "Value" ""
			(at 0 0 270)
			(layer "F.Fab")
			(effects
				(font
					(size 1.27 1.27)
				)
			)
		)
		(duplicate_pad_numbers_are_jumpers no)
		(fp_line
			(start -0.7874 0.4064)
			(end -0.7874 -0.4064)
			(stroke
				(width 0.1524)
				(type default)
			)
			(layer "F.SilkS")
		)
		(fp_line
			(start 0.7874 0.4064)
			(end -0.7874 0.4064)
			(stroke
				(width 0.1524)
				(type default)
			)
			(layer "F.SilkS")
		)
		(fp_line
			(start -0.7874 -0.4064)
			(end 0.7874 -0.4064)
			(stroke
				(width 0.1524)
				(type default)
			)
			(layer "F.SilkS")
		)
		(fp_line
			(start 0.7874 -0.4064)
			(end 0.7874 0.4064)
			(stroke
				(width 0.1524)
				(type default)
			)
			(layer "F.SilkS")
		)
		(fp_line
			(start -0.67945 0.3048)
			(end -0.67945 -0.305054)
			(stroke
				(width 0.1)
				(type default)
			)
			(layer "F.Fab")
		)
		(fp_line
			(start -0.12065 0.3048)
			(end -0.67945 0.3048)
			(stroke
				(width 0.1)
				(type default)
			)
			(layer "F.Fab")
		)
		(fp_line
			(start 0.120396 0.3048)
			(end 0.120396 0.2794)
			(stroke
				(width 0.1)
				(type default)
			)
			(layer "F.Fab")
		)
		(fp_line
			(start 0.67945 0.3048)
			(end 0.120396 0.3048)
			(stroke
				(width 0.1)
				(type default)
			)
			(layer "F.Fab")
		)
		(fp_line
			(start -0.12065 0.2794)
			(end -0.12065 0.3048)
			(stroke
				(width 0.1)
				(type default)
			)
			(layer "F.Fab")
		)
		(fp_line
			(start 0.120396 0.2794)
			(end -0.12065 0.2794)
			(stroke
				(width 0.1)
				(type default)
			)
			(layer "F.Fab")
		)
		(fp_line
			(start -0.12065 -0.2794)
			(end 0.12065 -0.2794)
			(stroke
				(width 0.1)
				(type default)
			)
			(layer "F.Fab")
		)
		(fp_line
			(start 0.12065 -0.2794)
			(end 0.12065 -0.3048)
			(stroke
				(width 0.1)
				(type default)
			)
			(layer "F.Fab")
		)
		(fp_line
			(start 0.12065 -0.3048)
			(end 0.67945 -0.3048)
			(stroke
				(width 0.1)
				(type default)
			)
			(layer "F.Fab")
		)
		(fp_line
			(start 0.67945 -0.3048)
			(end 0.67945 0.3048)
			(stroke
				(width 0.1)
				(type default)
			)
			(layer "F.Fab")
		)
		(fp_line
			(start -0.67945 -0.305054)
			(end -0.12065 -0.305054)
			(stroke
				(width 0.1)
				(type default)
			)
			(layer "F.Fab")
		)
		(fp_line
			(start -0.12065 -0.305054)
			(end -0.12065 -0.2794)
			(stroke
				(width 0.1)
				(type default)
			)
			(layer "F.Fab")
		)
		(pad "1" smd circle
			(at -0.40005 0 270)
			(size 0 0)
			(layers "F.Cu" "F.Mask" "F.Paste")
			(net "SMB_BIC_I2C6_MUX_NIC_ADC_R_SCL")
		)
		(pad "2" smd circle
			(at 0.40005 0 270)
			(size 0 0)
			(layers "F.Cu" "F.Mask" "F.Paste")
			(net "SMB_NIC4_ADC_SCL")
		)
	)
)
